#ISCELL
  pure_quanta quanta_title_block_c *
  *
#ISCELL
  pure_quanta_power cad_note *
  *
#CELL
  pure_quanta genoa_sp5 *
  page17_i159
#ISCELL
  mstr_standard offpage *
  page17_i160
#ISCELL
  mstr_standard offpage *
  page17_i161
#ISCELL
  mstr_standard tap *
  page17_i162
#ISCELL
  mstr_standard tap *
  page17_i163
#ISCELL
  mstr_standard tap *
  page17_i164
#ISCELL
  mstr_standard tap *
  page17_i165
#ISCELL
  mstr_standard tap *
  page17_i166
#ISCELL
  mstr_standard tap *
  page17_i167
#ISCELL
  mstr_standard tap *
  page17_i168
#ISCELL
  mstr_standard tap *
  page17_i169
#ISCELL
  mstr_standard tap *
  page17_i170
#ISCELL
  mstr_standard tap *
  page17_i171
#ISCELL
  mstr_standard tap *
  page17_i172
#ISCELL
  mstr_standard tap *
  page17_i173
#ISCELL
  mstr_standard tap *
  page17_i174
#ISCELL
  mstr_standard tap *
  page17_i175
#ISCELL
  mstr_standard tap *
  page17_i176
#ISCELL
  mstr_standard tap *
  page17_i177
#ISCELL
  mstr_standard tap *
  page17_i178
#ISCELL
  mstr_standard tap *
  page17_i179
#ISCELL
  mstr_standard tap *
  page17_i180
#ISCELL
  mstr_standard tap *
  page17_i181
#ISCELL
  mstr_standard tap *
  page17_i182
#ISCELL
  mstr_standard tap *
  page17_i183
#ISCELL
  mstr_standard tap *
  page17_i184
#ISCELL
  mstr_standard tap *
  page17_i185
#ISCELL
  mstr_standard tap *
  page17_i186
#ISCELL
  mstr_standard tap *
  page17_i187
#ISCELL
  mstr_standard tap *
  page17_i188
#ISCELL
  mstr_standard tap *
  page17_i189
#ISCELL
  mstr_standard tap *
  page17_i190
#ISCELL
  mstr_standard tap *
  page17_i191
#ISCELL
  mstr_standard tap *
  page17_i192
#ISCELL
  mstr_standard tap *
  page17_i193
#ISCELL
  mstr_standard tap *
  page17_i194
#ISCELL
  mstr_standard tap *
  page17_i195
#ISCELL
  mstr_standard offpage *
  page17_i196
#ISCELL
  mstr_standard tap *
  page17_i197
#ISCELL
  mstr_standard tap *
  page17_i198
#ISCELL
  mstr_standard tap *
  page17_i199
#ISCELL
  mstr_standard tap *
  page17_i200
#ISCELL
  mstr_standard tap *
  page17_i201
#ISCELL
  mstr_standard tap *
  page17_i202
#ISCELL
  mstr_standard tap *
  page17_i203
#ISCELL
  mstr_standard tap *
  page17_i204
#ISCELL
  mstr_standard tap *
  page17_i205
#ISCELL
  mstr_standard tap *
  page17_i206
#ISCELL
  mstr_standard tap *
  page17_i207
#ISCELL
  mstr_standard tap *
  page17_i208
#ISCELL
  mstr_standard tap *
  page17_i209
#ISCELL
  mstr_standard tap *
  page17_i210
#ISCELL
  mstr_standard tap *
  page17_i211
#ISCELL
  mstr_standard tap *
  page17_i212
#ISCELL
  mstr_standard tap *
  page17_i213
#ISCELL
  mstr_standard tap *
  page17_i214
#ISCELL
  mstr_standard tap *
  page17_i215
#ISCELL
  mstr_standard tap *
  page17_i216
#ISCELL
  mstr_standard tap *
  page17_i217
#ISCELL
  mstr_standard tap *
  page17_i218
#ISCELL
  mstr_standard tap *
  page17_i219
#ISCELL
  mstr_standard tap *
  page17_i220
#ISCELL
  mstr_standard tap *
  page17_i221
#ISCELL
  mstr_standard tap *
  page17_i222
#ISCELL
  mstr_standard tap *
  page17_i223
#ISCELL
  mstr_standard tap *
  page17_i224
#ISCELL
  mstr_standard tap *
  page17_i225
#ISCELL
  mstr_standard tap *
  page17_i226
#ISCELL
  mstr_standard tap *
  page17_i227
#ISCELL
  mstr_standard tap *
  page17_i228
#ISCELL
  mstr_standard tap *
  page17_i229
#ISCELL
  mstr_standard tap *
  page17_i230
#ISCELL
  mstr_standard tap *
  page17_i231
#ISCELL
  mstr_standard tap *
  page17_i232
#ISCELL
  mstr_standard tap *
  page17_i233
#ISCELL
  mstr_standard offpage *
  page17_i234
#ISCELL
  mstr_standard tap *
  page17_i235
#ISCELL
  mstr_standard tap *
  page17_i236
#ISCELL
  mstr_standard tap *
  page17_i237
#ISCELL
  mstr_standard tap *
  page17_i238
#ISCELL
  mstr_standard tap *
  page17_i239
#ISCELL
  mstr_standard tap *
  page17_i240
#ISCELL
  mstr_standard tap *
  page17_i241
#ISCELL
  mstr_standard tap *
  page17_i242
#ISCELL
  mstr_standard tap *
  page17_i243
#ISCELL
  mstr_standard tap *
  page17_i244
#ISCELL
  mstr_standard tap *
  page17_i245
#ISCELL
  mstr_standard tap *
  page17_i246
#ISCELL
  mstr_standard tap *
  page17_i247
#ISCELL
  mstr_standard tap *
  page17_i248
#ISCELL
  mstr_standard tap *
  page17_i249
#ISCELL
  mstr_standard tap *
  page17_i250
#ISCELL
  mstr_standard tap *
  page17_i251
#ISCELL
  mstr_standard tap *
  page17_i252
#ISCELL
  mstr_standard tap *
  page17_i253
#ISCELL
  mstr_standard tap *
  page17_i254
#ISCELL
  mstr_standard tap *
  page17_i255
#ISCELL
  mstr_standard tap *
  page17_i256
#ISCELL
  mstr_standard tap *
  page17_i257
#ISCELL
  mstr_standard tap *
  page17_i258
#ISCELL
  mstr_standard tap *
  page17_i259
#ISCELL
  mstr_standard tap *
  page17_i260
#ISCELL
  mstr_standard tap *
  page17_i261
#ISCELL
  mstr_standard tap *
  page17_i262
#ISCELL
  mstr_standard tap *
  page17_i263
#ISCELL
  mstr_standard tap *
  page17_i264
#ISCELL
  mstr_standard tap *
  page17_i265
#ISCELL
  mstr_standard tap *
  page17_i266
#ISCELL
  mstr_standard tap *
  page17_i267
#ISCELL
  mstr_standard tap *
  page17_i268
#ISCELL
  mstr_standard tap *
  page17_i269
#ISCELL
  mstr_standard tap *
  page17_i270
#ISCELL
  mstr_standard tap *
  page17_i271
#ISCELL
  mstr_standard tap *
  page17_i272
#ISCELL
  mstr_standard tap *
  page17_i273
#ISCELL
  mstr_standard tap *
  page17_i274
#ISCELL
  mstr_standard tap *
  page17_i275
#ISCELL
  mstr_standard tap *
  page17_i276
#ISCELL
  mstr_standard tap *
  page17_i277
#ISCELL
  mstr_standard tap *
  page17_i278
#ISCELL
  mstr_standard tap *
  page17_i279
#ISCELL
  mstr_standard tap *
  page17_i280
#ISCELL
  standard offpage *
  page17_i281
#ISCELL
  standard offpage *
  page17_i282
#ISCELL
  standard offpage *
  page17_i283
#ISCELL
  standard offpage *
  page17_i284
#ISCELL
  mstr_standard tap *
  page17_i285
#ISCELL
  mstr_standard tap *
  page17_i286
#ISCELL
  mstr_standard tap *
  page17_i287
#ISCELL
  mstr_standard tap *
  page17_i288
#ISCELL
  mstr_standard tap *
  page17_i289
#ISCELL
  mstr_standard tap *
  page17_i290
#ISCELL
  mstr_standard tap *
  page17_i291
#ISCELL
  mstr_standard tap *
  page17_i292
#ISCELL
  mstr_standard tap *
  page17_i293
#ISCELL
  mstr_standard tap *
  page17_i294
#ISCELL
  mstr_standard tap *
  page17_i295
#ISCELL
  mstr_standard tap *
  page17_i296
#ISCELL
  mstr_standard tap *
  page17_i297
#ISCELL
  mstr_standard tap *
  page17_i298
#ISCELL
  mstr_standard tap *
  page17_i299
#ISCELL
  mstr_standard tap *
  page17_i300
#ISCELL
  mstr_standard tap *
  page17_i301
#ISCELL
  standard offpage *
  page17_i302
#ISCELL
  standard offpage *
  page17_i303
#ISCELL
  standard offpage *
  page17_i304
#ISCELL
  standard offpage *
  page17_i305
#ISCELL
  standard offpage *
  page17_i306
#ISCELL
  standard offpage *
  page17_i307
#ISCELL
  standard offpage *
  page17_i308
#ISCELL
  mstr_standard offpage *
  page17_i309
#ISCELL
  standard offpage *
  page17_i310
#ISCELL
  standard offpage *
  page17_i311
#ISCELL
  standard offpage *
  page17_i312
#ISCELL
  standard offpage *
  page17_i313
#CELL
  pure_quanta q_res *
  page17_i314
#ISCELL
  mstr_standard offpage *
  page17_i315
#ISCELL
  standard offpage *
  page17_i316
